(kicad_pcb
	(version 20260206)
	(generator "pcbnew")
	(generator_version "10.0")
	(general
		(thickness 1.6)
		(legacy_teardrops no)
	)
	(paper "A4")
	(title_block
		(title "01162023_DA0F0TEBIF0_F0T_Expander_BD_F_brd_V02_OCP.brd")
		(comment 1 "Grand Teton / footprints 2335-2343 of 9728")
	)
	(layers
		(0 "F.Cu" signal "TOP")
		(4 "In1.Cu" signal "GND")
		(6 "In2.Cu" signal "VCC")
		(8 "In3.Cu" signal "VCC1")
		(10 "In4.Cu" signal "GND1")
		(12 "In5.Cu" signal "IN1")
		(14 "In6.Cu" signal "GND2")
		(16 "In7.Cu" signal "IN2")
		(18 "In8.Cu" signal "GND3")
		(20 "In9.Cu" signal "IN3")
		(22 "In10.Cu" signal "GND4")
		(24 "In11.Cu" signal "IN4")
		(26 "In12.Cu" signal "GND5")
		(28 "In13.Cu" signal "IN5")
		(30 "In14.Cu" signal "GND6")
		(32 "In15.Cu" signal "IN6")
		(34 "In16.Cu" signal "GND7")
		(2 "B.Cu" signal "BOTTOM")
		(9 "F.Adhes" user "F.Adhesive")
		(11 "B.Adhes" user "B.Adhesive")
		(13 "F.Paste" user "Package Geometry/Pastemask Top")
		(15 "B.Paste" user "Package Geometry/Pastemask Bottom")
		(5 "F.SilkS" user "Ref Des/Silkscreen Top")
		(7 "B.SilkS" user "Ref Des/Silkscreen Bottom")
		(1 "F.Mask" user "Board Geometry/Soldermask Top")
		(3 "B.Mask" user "Board Geometry/Soldermask Bottom")
		(17 "Dwgs.User" user "User.Drawings")
		(19 "Cmts.User" user "User.Comments")
		(21 "Eco1.User" user "User.Eco1")
		(23 "Eco2.User" user "User.Eco2")
		(25 "Edge.Cuts" user "Board Geometry/Outline")
		(27 "Margin" user)
		(31 "F.CrtYd" user "Package Geometry/Place Bound Top")
		(29 "B.CrtYd" user "Package Geometry/Place Bound Bottom")
		(35 "F.Fab" user "Ref Des/Assembly Top")
		(33 "B.Fab" user "Ref Des/Assembly Bottom")
	)
	(footprint ""
		(layer "F.Cu")
		(at 194.948048 -367.843308 -90)
		(property "Reference" "R6251"
			(at 0 0 270)
			(layer "F.SilkS")
			(hide yes)
			(effects
				(font
					(size 1.27 1.27)
				)
			)
		)
		(property "Value" ""
			(at 0 0 270)
			(layer "F.Fab")
			(effects
				(font
					(size 1.27 1.27)
				)
			)
		)
		(duplicate_pad_numbers_are_jumpers no)
		(fp_line
			(start -0.7874 0.4064)
			(end -0.7874 -0.4064)
			(stroke
				(width 0.1524)
				(type default)
			)
			(layer "F.SilkS")
		)
		(fp_line
			(start 0.7874 0.4064)
			(end -0.7874 0.4064)
			(stroke
				(width 0.1524)
				(type default)
			)
			(layer "F.SilkS")
		)
		(fp_line
			(start -0.7874 -0.4064)
			(end 0.7874 -0.4064)
			(stroke
				(width 0.1524)
				(type default)
			)
			(layer "F.SilkS")
		)
		(fp_line
			(start 0.7874 -0.4064)
			(end 0.7874 0.4064)
			(stroke
				(width 0.1524)
				(type default)
			)
			(layer "F.SilkS")
		)
		(fp_line
			(start -0.67945 0.3048)
			(end -0.67945 -0.305054)
			(stroke
				(width 0.1)
				(type default)
			)
			(layer "F.Fab")
		)
		(fp_line
			(start -0.12065 0.3048)
			(end -0.67945 0.3048)
			(stroke
				(width 0.1)
				(type default)
			)
			(layer "F.Fab")
		)
		(fp_line
			(start 0.120396 0.3048)
			(end 0.120396 0.2794)
			(stroke
				(width 0.1)
				(type default)
			)
			(layer "F.Fab")
		)
		(fp_line
			(start 0.67945 0.3048)
			(end 0.120396 0.3048)
			(stroke
				(width 0.1)
				(type default)
			)
			(layer "F.Fab")
		)
		(fp_line
			(start -0.12065 0.2794)
			(end -0.12065 0.3048)
			(stroke
				(width 0.1)
				(type default)
			)
			(layer "F.Fab")
		)
		(fp_line
			(start 0.120396 0.2794)
			(end -0.12065 0.2794)
			(stroke
				(width 0.1)
				(type default)
			)
			(layer "F.Fab")
		)
		(fp_line
			(start -0.12065 -0.2794)
			(end 0.12065 -0.2794)
			(stroke
				(width 0.1)
				(type default)
			)
			(layer "F.Fab")
		)
		(fp_line
			(start 0.12065 -0.2794)
			(end 0.12065 -0.3048)
			(stroke
				(width 0.1)
				(type default)
			)
			(layer "F.Fab")
		)
		(fp_line
			(start 0.12065 -0.3048)
			(end 0.67945 -0.3048)
			(stroke
				(width 0.1)
				(type default)
			)
			(layer "F.Fab")
		)
		(fp_line
			(start 0.67945 -0.3048)
			(end 0.67945 0.3048)
			(stroke
				(width 0.1)
				(type default)
			)
			(layer "F.Fab")
		)
		(fp_line
			(start -0.67945 -0.305054)
			(end -0.12065 -0.305054)
			(stroke
				(width 0.1)
				(type default)
			)
			(layer "F.Fab")
		)
		(fp_line
			(start -0.12065 -0.305054)
			(end -0.12065 -0.2794)
			(stroke
				(width 0.1)
				(type default)
			)
			(layer "F.Fab")
		)
		(pad "1" smd circle
			(at -0.40005 0 270)
			(size 0 0)
			(layers "F.Cu" "F.Mask" "F.Paste")
			(net "FM_HSC_PWROK")
		)
		(pad "2" smd circle
			(at 0.40005 0 270)
			(size 0 0)
			(layers "F.Cu" "F.Mask" "F.Paste")
			(net "PWRGD_P12V_AUX_R")
		)
	)
	(footprint ""
		(layer "F.Cu")
		(at 5.617718 -264.586466 180)
		(property "Reference" "L82"
			(at 0 0 180)
			(layer "F.SilkS")
			(hide yes)
			(effects
				(font
					(size 1.27 1.27)
				)
			)
		)
		(property "Value" ""
			(at 0 0 180)
			(layer "F.Fab")
			(effects
				(font
					(size 1.27 1.27)
				)
			)
		)
		(duplicate_pad_numbers_are_jumpers no)
		(fp_line
			(start 2.248154 4.9911)
			(end 2.248154 1.73482)
			(stroke
				(width 0.1524)
				(type default)
			)
			(layer "F.SilkS")
		)
		(fp_line
			(start 2.248154 -1.592072)
			(end 2.248154 -4.9911)
			(stroke
				(width 0.1524)
				(type default)
			)
			(layer "F.SilkS")
		)
		(fp_line
			(start 2.248154 -4.9911)
			(end -2.248154 -4.9911)
			(stroke
				(width 0.1524)
				(type default)
			)
			(layer "F.SilkS")
		)
		(fp_line
			(start -2.248154 4.9911)
			(end 2.248154 4.9911)
			(stroke
				(width 0.1524)
				(type default)
			)
			(layer "F.SilkS")
		)
		(fp_line
			(start -2.248154 1.646936)
			(end -2.248154 4.9911)
			(stroke
				(width 0.1524)
				(type default)
			)
			(layer "F.SilkS")
		)
		(fp_line
			(start -2.248154 -4.9911)
			(end -2.248154 -1.690878)
			(stroke
				(width 0.1524)
				(type default)
			)
			(layer "F.SilkS")
		)
		(fp_line
			(start 1.700022 0.899922)
			(end 1.700022 -0.899922)
			(stroke
				(width 0.1)
				(type default)
			)
			(layer "F.Fab")
		)
		(fp_line
			(start 1.700022 -0.899922)
			(end -1.700022 -0.899922)
			(stroke
				(width 0.1)
				(type default)
			)
			(layer "F.Fab")
		)
		(fp_line
			(start -1.700022 0.899922)
			(end 1.700022 0.899922)
			(stroke
				(width 0.1)
				(type default)
			)
			(layer "F.Fab")
		)
		(fp_line
			(start -1.700022 -0.899922)
			(end -1.700022 0.899922)
			(stroke
				(width 0.1)
				(type default)
			)
			(layer "F.Fab")
		)
		(pad "1" smd rect
			(at -1.575054 0 180)
			(size 1.1684 9.8044)
			(layers "F.Cu" "F.Mask" "F.Paste")
			(net "P1V25_PEX0")
		)
		(pad "2" smd rect
			(at 1.575054 0 180)
			(size 1.1684 9.8044)
			(layers "F.Cu" "F.Mask" "F.Paste")
			(net "P1V25_SERDES_VDDPLL_PEX0")
		)
	)
	(footprint ""
		(layer "F.Cu")
		(at 475.10827 -524.295624 180)
		(property "Reference" "SCREW_SSD4_2"
			(at -5.207 -1.402334 0)
			(unlocked yes)
			(layer "B.SilkS")
			(effects
				(font
					(size 0.7874 0.5842)
					(thickness 0.1524)
				)
				(justify mirror)
			)
		)
		(property "Value" ""
			(at 0 0 180)
			(layer "F.Fab")
			(effects
				(font
					(size 1.27 1.27)
				)
			)
		)
		(duplicate_pad_numbers_are_jumpers no)
		(pad "1" thru_hole circle
			(at 0 0 180)
			(size 0.4572 0.4572)
			(drill 0.2032)
			(layers "*.Cu" "*.Mask")
			(remove_unused_layers no)
			(net "Net_9135")
			(clearance 0.127)
			(thermal_gap 0.127)
			(padstack
				(mode front_inner_back)
				(layer "Inner"
					(shape circle)
					(size 0.4572 0.4572)
					(clearance 0.127)
				)
				(layer "B.Cu"
					(shape circle)
					(size 0.508 0.508)
					(clearance 0.1016)
				)
			)
		)
	)
	(footprint ""
		(layer "F.Cu")
		(at 10.11047 -121.661428 180)
		(property "Reference" "C2877"
			(at 0 0 180)
			(layer "F.SilkS")
			(hide yes)
			(effects
				(font
					(size 1.27 1.27)
				)
			)
		)
		(property "Value" ""
			(at 0 0 180)
			(layer "F.Fab")
			(effects
				(font
					(size 1.27 1.27)
				)
			)
		)
		(duplicate_pad_numbers_are_jumpers no)
		(fp_line
			(start 0.7874 0.4064)
			(end -0.7874 0.4064)
			(stroke
				(width 0.1524)
				(type default)
			)
			(layer "F.SilkS")
		)
		(fp_line
			(start 0.7874 -0.4064)
			(end 0.7874 0.4064)
			(stroke
				(width 0.1524)
				(type default)
			)
			(layer "F.SilkS")
		)
		(fp_line
			(start -0.7874 0.4064)
			(end -0.7874 -0.4064)
			(stroke
				(width 0.1524)
				(type default)
			)
			(layer "F.SilkS")
		)
		(fp_line
			(start -0.7874 -0.4064)
			(end 0.7874 -0.4064)
			(stroke
				(width 0.1524)
				(type default)
			)
			(layer "F.SilkS")
		)
		(fp_line
			(start 0.67945 0.3048)
			(end 0.120396 0.3048)
			(stroke
				(width 0.1)
				(type default)
			)
			(layer "F.Fab")
		)
		(fp_line
			(start 0.67945 -0.3048)
			(end 0.67945 0.3048)
			(stroke
				(width 0.1)
				(type default)
			)
			(layer "F.Fab")
		)
		(fp_line
			(start 0.12065 -0.2794)
			(end 0.12065 -0.3048)
			(stroke
				(width 0.1)
				(type default)
			)
			(layer "F.Fab")
		)
		(fp_line
			(start 0.12065 -0.3048)
			(end 0.67945 -0.3048)
			(stroke
				(width 0.1)
				(type default)
			)
			(layer "F.Fab")
		)
		(fp_line
			(start 0.120396 0.3048)
			(end 0.120396 0.2794)
			(stroke
				(width 0.1)
				(type default)
			)
			(layer "F.Fab")
		)
		(fp_line
			(start 0.120396 0.2794)
			(end -0.12065 0.2794)
			(stroke
				(width 0.1)
				(type default)
			)
			(layer "F.Fab")
		)
		(fp_line
			(start -0.12065 0.3048)
			(end -0.67945 0.3048)
			(stroke
				(width 0.1)
				(type default)
			)
			(layer "F.Fab")
		)
		(fp_line
			(start -0.12065 0.2794)
			(end -0.12065 0.3048)
			(stroke
				(width 0.1)
				(type default)
			)
			(layer "F.Fab")
		)
		(fp_line
			(start -0.12065 -0.2794)
			(end 0.12065 -0.2794)
			(stroke
				(width 0.1)
				(type default)
			)
			(layer "F.Fab")
		)
		(fp_line
			(start -0.12065 -0.305054)
			(end -0.12065 -0.2794)
			(stroke
				(width 0.1)
				(type default)
			)
			(layer "F.Fab")
		)
		(fp_line
			(start -0.67945 0.3048)
			(end -0.67945 -0.305054)
			(stroke
				(width 0.1)
				(type default)
			)
			(layer "F.Fab")
		)
		(fp_line
			(start -0.67945 -0.305054)
			(end -0.12065 -0.305054)
			(stroke
				(width 0.1)
				(type default)
			)
			(layer "F.Fab")
		)
		(pad "1" smd circle
			(at -0.40005 0 180)
			(size 0 0)
			(layers "F.Cu" "F.Mask" "F.Paste")
			(net "HP_NIC0_EN")
		)
		(pad "2" smd circle
			(at 0.40005 0 180)
			(size 0 0)
			(layers "F.Cu" "F.Mask" "F.Paste")
			(net "GND")
		)
	)
	(footprint ""
		(layer "F.Cu")
		(at 152.738328 -111.895382)
		(property "Reference" "C260"
			(at 0 0 0)
			(layer "F.SilkS")
			(hide yes)
			(effects
				(font
					(size 1.27 1.27)
				)
			)
		)
		(property "Value" ""
			(at 0 0 0)
			(layer "F.Fab")
			(effects
				(font
					(size 1.27 1.27)
				)
			)
		)
		(duplicate_pad_numbers_are_jumpers no)
		(fp_line
			(start -0.299974 -0.150114)
			(end 0.299974 -0.150114)
			(stroke
				(width 0.1)
				(type default)
			)
			(layer "F.Fab")
		)
		(fp_line
			(start -0.299974 0.150114)
			(end -0.299974 -0.150114)
			(stroke
				(width 0.1)
				(type default)
			)
			(layer "F.Fab")
		)
		(fp_line
			(start 0.299974 -0.150114)
			(end 0.299974 0.150114)
			(stroke
				(width 0.1)
				(type default)
			)
			(layer "F.Fab")
		)
		(fp_line
			(start 0.299974 0.150114)
			(end -0.299974 0.150114)
			(stroke
				(width 0.1)
				(type default)
			)
			(layer "F.Fab")
		)
		(pad "1" smd rect
			(at -0.2667 0)
			(size 0.3048 0.381)
			(layers "F.Cu" "F.Mask" "F.Paste")
			(net "P5E_PEX1_STN1_TX_DN<23>")
		)
		(pad "2" smd rect
			(at 0.2667 0)
			(size 0.3048 0.381)
			(layers "F.Cu" "F.Mask" "F.Paste")
			(net "P5E_PEX1_STN1_TX_C_DN<23>")
		)
	)
	(footprint ""
		(layer "F.Cu")
		(at 71.7042 -235.690156 90)
		(property "Reference" "R6639"
			(at 0 0 90)
			(layer "F.SilkS")
			(hide yes)
			(effects
				(font
					(size 1.27 1.27)
				)
			)
		)
		(property "Value" ""
			(at 0 0 90)
			(layer "F.Fab")
			(effects
				(font
					(size 1.27 1.27)
				)
			)
		)
		(duplicate_pad_numbers_are_jumpers no)
		(fp_line
			(start 0.7874 -0.4064)
			(end 0.7874 0.4064)
			(stroke
				(width 0.1524)
				(type default)
			)
			(layer "F.SilkS")
		)
		(fp_line
			(start -0.7874 -0.4064)
			(end 0.7874 -0.4064)
			(stroke
				(width 0.1524)
				(type default)
			)
			(layer "F.SilkS")
		)
		(fp_line
			(start 0.7874 0.4064)
			(end -0.7874 0.4064)
			(stroke
				(width 0.1524)
				(type default)
			)
			(layer "F.SilkS")
		)
		(fp_line
			(start -0.7874 0.4064)
			(end -0.7874 -0.4064)
			(stroke
				(width 0.1524)
				(type default)
			)
			(layer "F.SilkS")
		)
		(fp_line
			(start -0.12065 -0.305054)
			(end -0.12065 -0.2794)
			(stroke
				(width 0.1)
				(type default)
			)
			(layer "F.Fab")
		)
		(fp_line
			(start -0.67945 -0.305054)
			(end -0.12065 -0.305054)
			(stroke
				(width 0.1)
				(type default)
			)
			(layer "F.Fab")
		)
		(fp_line
			(start 0.67945 -0.3048)
			(end 0.67945 0.3048)
			(stroke
				(width 0.1)
				(type default)
			)
			(layer "F.Fab")
		)
		(fp_line
			(start 0.12065 -0.3048)
			(end 0.67945 -0.3048)
			(stroke
				(width 0.1)
				(type default)
			)
			(layer "F.Fab")
		)
		(fp_line
			(start 0.12065 -0.2794)
			(end 0.12065 -0.3048)
			(stroke
				(width 0.1)
				(type default)
			)
			(layer "F.Fab")
		)
		(fp_line
			(start -0.12065 -0.2794)
			(end 0.12065 -0.2794)
			(stroke
				(width 0.1)
				(type default)
			)
			(layer "F.Fab")
		)
		(fp_line
			(start 0.120396 0.2794)
			(end -0.12065 0.2794)
			(stroke
				(width 0.1)
				(type default)
			)
			(layer "F.Fab")
		)
		(fp_line
			(start -0.12065 0.2794)
			(end -0.12065 0.3048)
			(stroke
				(width 0.1)
				(type default)
			)
			(layer "F.Fab")
		)
		(fp_line
			(start 0.67945 0.3048)
			(end 0.120396 0.3048)
			(stroke
				(width 0.1)
				(type default)
			)
			(layer "F.Fab")
		)
		(fp_line
			(start 0.120396 0.3048)
			(end 0.120396 0.2794)
			(stroke
				(width 0.1)
				(type default)
			)
			(layer "F.Fab")
		)
		(fp_line
			(start -0.12065 0.3048)
			(end -0.67945 0.3048)
			(stroke
				(width 0.1)
				(type default)
			)
			(layer "F.Fab")
		)
		(fp_line
			(start -0.67945 0.3048)
			(end -0.67945 -0.305054)
			(stroke
				(width 0.1)
				(type default)
			)
			(layer "F.Fab")
		)
		(pad "1" smd circle
			(at -0.40005 0 90)
			(size 0 0)
			(layers "F.Cu" "F.Mask" "F.Paste")
			(net "UART_PEX0_CLI_R_RX")
		)
		(pad "2" smd circle
			(at 0.40005 0 90)
			(size 0 0)
			(layers "F.Cu" "F.Mask" "F.Paste")
			(net "UART_PEX0_CLI_R1_RX")
		)
	)
	(footprint ""
		(layer "F.Cu")
		(at 260.249162 -293.796212 -90)
		(property "Reference" "C3386"
			(at 0 0 270)
			(layer "F.SilkS")
			(hide yes)
			(effects
				(font
					(size 1.27 1.27)
				)
			)
		)
		(property "Value" ""
			(at 0 0 270)
			(layer "F.Fab")
			(effects
				(font
					(size 1.27 1.27)
				)
			)
		)
		(duplicate_pad_numbers_are_jumpers no)
		(fp_line
			(start -0.299974 0.150114)
			(end -0.299974 -0.150114)
			(stroke
				(width 0.1)
				(type default)
			)
			(layer "F.Fab")
		)
		(fp_line
			(start 0.299974 0.150114)
			(end -0.299974 0.150114)
			(stroke
				(width 0.1)
				(type default)
			)
			(layer "F.Fab")
		)
		(fp_line
			(start -0.299974 -0.150114)
			(end 0.299974 -0.150114)
			(stroke
				(width 0.1)
				(type default)
			)
			(layer "F.Fab")
		)
		(fp_line
			(start 0.299974 -0.150114)
			(end 0.299974 0.150114)
			(stroke
				(width 0.1)
				(type default)
			)
			(layer "F.Fab")
		)
		(pad "1" smd rect
			(at -0.2667 0 270)
			(size 0.3048 0.381)
			(layers "F.Cu" "F.Mask" "F.Paste")
			(net "P1V8_PLL0_PEX2")
		)
		(pad "2" smd rect
			(at 0.2667 0 270)
			(size 0.3048 0.381)
			(layers "F.Cu" "F.Mask" "F.Paste")
			(net "GND")
		)
	)
	(footprint ""
		(layer "F.Cu")
		(at 200.011538 -405.901144 -90)
		(property "Reference" "R6253"
			(at 0 0 270)
			(layer "F.SilkS")
			(hide yes)
			(effects
				(font
					(size 1.27 1.27)
				)
			)
		)
		(property "Value" ""
			(at 0 0 270)
			(layer "F.Fab")
			(effects
				(font
					(size 1.27 1.27)
				)
			)
		)
		(duplicate_pad_numbers_are_jumpers no)
		(fp_line
			(start -0.7874 0.4064)
			(end -0.7874 -0.4064)
			(stroke
				(width 0.1524)
				(type default)
			)
			(layer "F.SilkS")
		)
		(fp_line
			(start 0.7874 0.4064)
			(end -0.7874 0.4064)
			(stroke
				(width 0.1524)
				(type default)
			)
			(layer "F.SilkS")
		)
		(fp_line
			(start -0.7874 -0.4064)
			(end 0.7874 -0.4064)
			(stroke
				(width 0.1524)
				(type default)
			)
			(layer "F.SilkS")
		)
		(fp_line
			(start 0.7874 -0.4064)
			(end 0.7874 0.4064)
			(stroke
				(width 0.1524)
				(type default)
			)
			(layer "F.SilkS")
		)
		(fp_line
			(start -0.67945 0.3048)
			(end -0.67945 -0.305054)
			(stroke
				(width 0.1)
				(type default)
			)
			(layer "F.Fab")
		)
		(fp_line
			(start -0.12065 0.3048)
			(end -0.67945 0.3048)
			(stroke
				(width 0.1)
				(type default)
			)
			(layer "F.Fab")
		)
		(fp_line
			(start 0.120396 0.3048)
			(end 0.120396 0.2794)
			(stroke
				(width 0.1)
				(type default)
			)
			(layer "F.Fab")
		)
		(fp_line
			(start 0.67945 0.3048)
			(end 0.120396 0.3048)
			(stroke
				(width 0.1)
				(type default)
			)
			(layer "F.Fab")
		)
		(fp_line
			(start -0.12065 0.2794)
			(end -0.12065 0.3048)
			(stroke
				(width 0.1)
				(type default)
			)
			(layer "F.Fab")
		)
		(fp_line
			(start 0.120396 0.2794)
			(end -0.12065 0.2794)
			(stroke
				(width 0.1)
				(type default)
			)
			(layer "F.Fab")
		)
		(fp_line
			(start -0.12065 -0.2794)
			(end 0.12065 -0.2794)
			(stroke
				(width 0.1)
				(type default)
			)
			(layer "F.Fab")
		)
		(fp_line
			(start 0.12065 -0.2794)
			(end 0.12065 -0.3048)
			(stroke
				(width 0.1)
				(type default)
			)
			(layer "F.Fab")
		)
		(fp_line
			(start 0.12065 -0.3048)
			(end 0.67945 -0.3048)
			(stroke
				(width 0.1)
				(type default)
			)
			(layer "F.Fab")
		)
		(fp_line
			(start 0.67945 -0.3048)
			(end 0.67945 0.3048)
			(stroke
				(width 0.1)
				(type default)
			)
			(layer "F.Fab")
		)
		(fp_line
			(start -0.67945 -0.305054)
			(end -0.12065 -0.305054)
			(stroke
				(width 0.1)
				(type default)
			)
			(layer "F.Fab")
		)
		(fp_line
			(start -0.12065 -0.305054)
			(end -0.12065 -0.2794)
			(stroke
				(width 0.1)
				(type default)
			)
			(layer "F.Fab")
		)
		(pad "1" smd circle
			(at -0.40005 0 270)
			(size 0 0)
			(layers "F.Cu" "F.Mask" "F.Paste")
			(net "MB_HSC_EN")
		)
		(pad "2" smd circle
			(at 0.40005 0 270)
			(size 0 0)
			(layers "F.Cu" "F.Mask" "F.Paste")
			(net "GND")
		)
	)
	(footprint ""
		(layer "F.Cu")
		(at 98.434398 -33.631886 180)
		(property "Reference" "C90"
			(at 0 0 180)
			(layer "F.SilkS")
			(hide yes)
			(effects
				(font
					(size 1.27 1.27)
				)
			)
		)
		(property "Value" ""
			(at 0 0 180)
			(layer "F.Fab")
			(effects
				(font
					(size 1.27 1.27)
				)
			)
		)
		(duplicate_pad_numbers_are_jumpers no)
		(fp_line
			(start 0.299974 0.150114)
			(end -0.299974 0.150114)
			(stroke
				(width 0.1)
				(type default)
			)
			(layer "F.Fab")
		)
		(fp_line
			(start 0.299974 -0.150114)
			(end 0.299974 0.150114)
			(stroke
				(width 0.1)
				(type default)
			)
			(layer "F.Fab")
		)
		(fp_line
			(start -0.299974 0.150114)
			(end -0.299974 -0.150114)
			(stroke
				(width 0.1)
				(type default)
			)
			(layer "F.Fab")
		)
		(fp_line
			(start -0.299974 -0.150114)
			(end 0.299974 -0.150114)
			(stroke
				(width 0.1)
				(type default)
			)
			(layer "F.Fab")
		)
		(pad "1" smd rect
			(at -0.2667 0 180)
			(size 0.3048 0.381)
			(layers "F.Cu" "F.Mask" "F.Paste")
			(net "P5E_PEX0_STN2_TX_DN<35>")
		)
		(pad "2" smd rect
			(at 0.2667 0 180)
			(size 0.3048 0.381)
			(layers "F.Cu" "F.Mask" "F.Paste")
			(net "P5E_PEX0_STN2_TX_C_DN<35>")
		)
	)
)
